(kicad_pcb
	(version 20260206)
	(generator "pcbnew")
	(generator_version "10.0")
	(general
		(thickness 1.6)
		(legacy_teardrops no)
	)
	(paper "A4")
	(title_block
		(title "peb — Lightning_PEB_BRD.brd")
		(comment 1 "Lightning (Wiwynn / Facebook NVMe JBOF) / footprints 1896-1902 of 2563")
	)
	(layers
		(0 "F.Cu" signal "TOP")
		(4 "In1.Cu" signal "L2GND")
		(6 "In2.Cu" signal "L3")
		(8 "In3.Cu" signal "L4VCC")
		(10 "In4.Cu" signal "L5VCC")
		(12 "In5.Cu" signal "L6")
		(14 "In6.Cu" signal "L7GND")
		(2 "B.Cu" signal "BOTTOM")
		(9 "F.Adhes" user "F.Adhesive")
		(11 "B.Adhes" user "B.Adhesive")
		(13 "F.Paste" user "Package Geometry/Pastemask Top")
		(15 "B.Paste" user "Package Geometry/Pastemask Bottom")
		(5 "F.SilkS" user "Ref Des/Silkscreen Top")
		(7 "B.SilkS" user "Ref Des/Silkscreen Bottom")
		(1 "F.Mask" user "Board Geometry/Soldermask Top")
		(3 "B.Mask" user "Board Geometry/Soldermask Bottom")
		(17 "Dwgs.User" user "User.Drawings")
		(19 "Cmts.User" user "User.Comments")
		(21 "Eco1.User" user "User.Eco1")
		(23 "Eco2.User" user "User.Eco2")
		(25 "Edge.Cuts" user "Board Geometry/Outline")
		(27 "Margin" user)
		(31 "F.CrtYd" user "Package Geometry/Place Bound Top")
		(29 "B.CrtYd" user "Package Geometry/Place Bound Bottom")
		(35 "F.Fab" user "Ref Des/Assembly Top")
		(33 "B.Fab" user "Ref Des/Assembly Bottom")
	)
	(footprint ""
		(layer "B.Cu")
		(at 213.614 -197.231)
		(property "Reference" "R271"
			(at 0 0 0)
			(layer "B.SilkS")
			(hide yes)
			(effects
				(font
					(size 1.27 1.27)
				)
				(justify mirror)
			)
		)
		(property "Value" "4K7R2F-GP"
			(at -0.064008 -3.993896 0)
			(unlocked yes)
			(layer "B.Fab")
			(hide yes)
			(effects
				(font
					(size 1.016 1.016)
					(thickness 0.1524)
				)
				(justify mirror)
			)
		)
		(property "Device Type" "R402H16"
			(at -0.064008 -5.517896 0)
			(unlocked yes)
			(layer "B.Fab")
			(hide yes)
			(effects
				(font
					(size 1.016 1.016)
					(thickness 0.1524)
				)
				(justify mirror)
			)
		)
		(duplicate_pad_numbers_are_jumpers no)
		(fp_line
			(start -0.508 -0.9398)
			(end 0.508 -0.9398)
			(stroke
				(width 0.1524)
				(type default)
			)
			(layer "B.SilkS")
		)
		(fp_line
			(start 0.508 -0.9398)
			(end 0.508 0.9398)
			(stroke
				(width 0.1524)
				(type default)
			)
			(layer "B.SilkS")
		)
		(fp_rect
			(start 0.508 0.9398)
			(end -0.508 -0.9398)
			(stroke
				(width 0)
				(type default)
			)
			(fill no)
			(layer "B.CrtYd")
		)
		(fp_rect
			(start 0.508 0.9398)
			(end -0.508 -0.9398)
			(stroke
				(width 0)
				(type default)
			)
			(fill no)
			(layer "B.Fab")
		)
		(pad "1" smd custom
			(at 0 -0.4445 180)
			(size 0.1397 0.1397)
			(layers "B.Cu" "B.Mask" "B.Paste")
			(net "BMC_SSD_RST#0_A13")
			(options
				(clearance outline)
				(anchor circle)
			)
			(primitives
				(gr_poly
					(pts
						(arc
							(start -0.1778 0.2794)
							(mid -0.249642 0.249642)
							(end -0.2794 0.1778)
						)
						(arc
							(start -0.2794 -0.1778)
							(mid -0.249642 -0.249642)
							(end -0.1778 -0.2794)
						)
						(arc
							(start 0.1778 -0.2794)
							(mid 0.249642 -0.249642)
							(end 0.2794 -0.1778)
						)
						(arc
							(start 0.2794 0.1778)
							(mid 0.249642 0.249642)
							(end 0.1778 0.2794)
						)
					)
					(width 0)
					(fill yes)
				)
			)
		)
		(pad "2" smd custom
			(at 0 0.4445 180)
			(size 0.1397 0.1397)
			(layers "B.Cu" "B.Mask" "B.Paste")
			(net "P3V3_STBY")
			(options
				(clearance outline)
				(anchor circle)
			)
			(primitives
				(gr_poly
					(pts
						(arc
							(start -0.1778 0.2794)
							(mid -0.249642 0.249642)
							(end -0.2794 0.1778)
						)
						(arc
							(start -0.2794 -0.1778)
							(mid -0.249642 -0.249642)
							(end -0.1778 -0.2794)
						)
						(arc
							(start 0.1778 -0.2794)
							(mid 0.249642 -0.249642)
							(end 0.2794 -0.1778)
						)
						(arc
							(start 0.2794 0.1778)
							(mid 0.249642 0.249642)
							(end 0.1778 0.2794)
						)
					)
					(width 0)
					(fill yes)
				)
			)
		)
	)
	(footprint ""
		(layer "B.Cu")
		(at 13.507212 -74.913236 90)
		(property "Reference" "C629"
			(at 0 0 90)
			(layer "B.SilkS")
			(hide yes)
			(effects
				(font
					(size 1.27 1.27)
				)
				(justify mirror)
			)
		)
		(property "Value" "SCD1U16V2KX-3GP"
			(at -1.1811 -2.7051 90)
			(unlocked yes)
			(layer "B.Fab")
			(hide yes)
			(effects
				(font
					(size 1.016 1.016)
					(thickness 0.1524)
				)
				(justify mirror)
			)
		)
		(property "Device Type" "C402H22"
			(at -1.1811 -4.2291 90)
			(unlocked yes)
			(layer "B.Fab")
			(hide yes)
			(effects
				(font
					(size 1.016 1.016)
					(thickness 0.1524)
				)
				(justify mirror)
			)
		)
		(duplicate_pad_numbers_are_jumpers no)
		(fp_rect
			(start 0.4318 0.9525)
			(end -0.4318 -0.9525)
			(stroke
				(width 0)
				(type default)
			)
			(fill no)
			(layer "B.CrtYd")
		)
		(fp_rect
			(start 0.4318 0.9525)
			(end -0.4318 -0.9525)
			(stroke
				(width 0)
				(type default)
			)
			(fill no)
			(layer "B.Fab")
		)
		(pad "1" smd custom
			(at 0 -0.4445 270)
			(size 0.1524 0.1524)
			(layers "B.Cu" "B.Mask" "B.Paste")
			(net "P3V3_STBY")
			(options
				(clearance outline)
				(anchor circle)
			)
			(primitives
				(gr_poly
					(pts
						(arc
							(start 0.3048 0.2032)
							(mid 0.275042 0.275042)
							(end 0.2032 0.3048)
						)
						(arc
							(start -0.2032 0.3048)
							(mid -0.275042 0.275042)
							(end -0.3048 0.2032)
						)
						(arc
							(start -0.3048 -0.2032)
							(mid -0.275042 -0.275042)
							(end -0.2032 -0.3048)
						)
						(arc
							(start 0.2032 -0.3048)
							(mid 0.275042 -0.275042)
							(end 0.3048 -0.2032)
						)
					)
					(width 0)
					(fill yes)
				)
			)
		)
		(pad "2" smd custom
			(at 0 0.4445 270)
			(size 0.1524 0.1524)
			(layers "B.Cu" "B.Mask" "B.Paste")
			(net "GND")
			(options
				(clearance outline)
				(anchor circle)
			)
			(primitives
				(gr_poly
					(pts
						(arc
							(start 0.3048 0.2032)
							(mid 0.275042 0.275042)
							(end 0.2032 0.3048)
						)
						(arc
							(start -0.2032 0.3048)
							(mid -0.275042 0.275042)
							(end -0.3048 0.2032)
						)
						(arc
							(start -0.3048 -0.2032)
							(mid -0.275042 -0.275042)
							(end -0.2032 -0.3048)
						)
						(arc
							(start 0.2032 -0.3048)
							(mid 0.275042 -0.275042)
							(end 0.3048 -0.2032)
						)
					)
					(width 0)
					(fill yes)
				)
			)
		)
	)
	(footprint ""
		(layer "B.Cu")
		(at 127.972058 -33.503616 180)
		(property "Reference" "C220"
			(at 0 0 0)
			(layer "B.SilkS")
			(hide yes)
			(effects
				(font
					(size 1.27 1.27)
				)
				(justify mirror)
			)
		)
		(property "Value" "SCD1U10V2KX-5GP"
			(at -1.1811 -2.7051 180)
			(unlocked yes)
			(layer "B.Fab")
			(hide yes)
			(effects
				(font
					(size 1.016 1.016)
					(thickness 0.1524)
				)
				(justify mirror)
			)
		)
		(property "Device Type" "C402H22"
			(at -1.1811 -4.2291 180)
			(unlocked yes)
			(layer "B.Fab")
			(hide yes)
			(effects
				(font
					(size 1.016 1.016)
					(thickness 0.1524)
				)
				(justify mirror)
			)
		)
		(duplicate_pad_numbers_are_jumpers no)
		(fp_rect
			(start 0.4318 0.9525)
			(end -0.4318 -0.9525)
			(stroke
				(width 0)
				(type default)
			)
			(fill no)
			(layer "B.CrtYd")
		)
		(fp_rect
			(start 0.4318 0.9525)
			(end -0.4318 -0.9525)
			(stroke
				(width 0)
				(type default)
			)
			(fill no)
			(layer "B.Fab")
		)
		(pad "1" smd custom
			(at 0 -0.4445)
			(size 0.1524 0.1524)
			(layers "B.Cu" "B.Mask" "B.Paste")
			(net "GND")
			(options
				(clearance outline)
				(anchor circle)
			)
			(primitives
				(gr_poly
					(pts
						(arc
							(start 0.3048 0.2032)
							(mid 0.275042 0.275042)
							(end 0.2032 0.3048)
						)
						(arc
							(start -0.2032 0.3048)
							(mid -0.275042 0.275042)
							(end -0.3048 0.2032)
						)
						(arc
							(start -0.3048 -0.2032)
							(mid -0.275042 -0.275042)
							(end -0.2032 -0.3048)
						)
						(arc
							(start 0.2032 -0.3048)
							(mid 0.275042 -0.275042)
							(end 0.3048 -0.2032)
						)
					)
					(width 0)
					(fill yes)
				)
			)
		)
		(pad "2" smd custom
			(at 0 0.4445)
			(size 0.1524 0.1524)
			(layers "B.Cu" "B.Mask" "B.Paste")
			(net "P3V3_STBY")
			(options
				(clearance outline)
				(anchor circle)
			)
			(primitives
				(gr_poly
					(pts
						(arc
							(start 0.3048 0.2032)
							(mid 0.275042 0.275042)
							(end 0.2032 0.3048)
						)
						(arc
							(start -0.2032 0.3048)
							(mid -0.275042 0.275042)
							(end -0.3048 0.2032)
						)
						(arc
							(start -0.3048 -0.2032)
							(mid -0.275042 -0.275042)
							(end -0.2032 -0.3048)
						)
						(arc
							(start 0.2032 -0.3048)
							(mid 0.275042 -0.275042)
							(end 0.3048 -0.2032)
						)
					)
					(width 0)
					(fill yes)
				)
			)
		)
	)
	(footprint ""
		(layer "B.Cu")
		(at 18.3642 -138.6078 90)
		(property "Reference" "R2978"
			(at 0 0 90)
			(layer "B.SilkS")
			(hide yes)
			(effects
				(font
					(size 1.27 1.27)
				)
				(justify mirror)
			)
		)
		(property "Value" "10KR2F-2-GP"
			(at -0.064008 -3.993896 90)
			(unlocked yes)
			(layer "B.Fab")
			(hide yes)
			(effects
				(font
					(size 1.016 1.016)
					(thickness 0.1524)
				)
				(justify mirror)
			)
		)
		(property "Device Type" "R402H16"
			(at -0.064008 -5.517896 90)
			(unlocked yes)
			(layer "B.Fab")
			(hide yes)
			(effects
				(font
					(size 1.016 1.016)
					(thickness 0.1524)
				)
				(justify mirror)
			)
		)
		(duplicate_pad_numbers_are_jumpers no)
		(fp_line
			(start 0.508 -0.9398)
			(end 0.508 0.9398)
			(stroke
				(width 0.1524)
				(type default)
			)
			(layer "B.SilkS")
		)
		(fp_line
			(start -0.508 -0.9398)
			(end 0.508 -0.9398)
			(stroke
				(width 0.1524)
				(type default)
			)
			(layer "B.SilkS")
		)
		(fp_rect
			(start 0.508 0.9398)
			(end -0.508 -0.9398)
			(stroke
				(width 0)
				(type default)
			)
			(fill no)
			(layer "B.CrtYd")
		)
		(fp_rect
			(start 0.508 0.9398)
			(end -0.508 -0.9398)
			(stroke
				(width 0)
				(type default)
			)
			(fill no)
			(layer "B.Fab")
		)
		(pad "1" smd custom
			(at 0 -0.4445 270)
			(size 0.1397 0.1397)
			(layers "B.Cu" "B.Mask" "B.Paste")
			(net "P3V3_STBY")
			(options
				(clearance outline)
				(anchor circle)
			)
			(primitives
				(gr_poly
					(pts
						(arc
							(start -0.1778 0.2794)
							(mid -0.249642 0.249642)
							(end -0.2794 0.1778)
						)
						(arc
							(start -0.2794 -0.1778)
							(mid -0.249642 -0.249642)
							(end -0.1778 -0.2794)
						)
						(arc
							(start 0.1778 -0.2794)
							(mid 0.249642 -0.249642)
							(end 0.2794 -0.1778)
						)
						(arc
							(start 0.2794 0.1778)
							(mid 0.249642 0.249642)
							(end 0.1778 0.2794)
						)
					)
					(width 0)
					(fill yes)
				)
			)
		)
		(pad "2" smd custom
			(at 0 0.4445 270)
			(size 0.1397 0.1397)
			(layers "B.Cu" "B.Mask" "B.Paste")
			(net "BP_PRSNT_N")
			(options
				(clearance outline)
				(anchor circle)
			)
			(primitives
				(gr_poly
					(pts
						(arc
							(start -0.1778 0.2794)
							(mid -0.249642 0.249642)
							(end -0.2794 0.1778)
						)
						(arc
							(start -0.2794 -0.1778)
							(mid -0.249642 -0.249642)
							(end -0.1778 -0.2794)
						)
						(arc
							(start 0.1778 -0.2794)
							(mid 0.249642 -0.249642)
							(end 0.2794 -0.1778)
						)
						(arc
							(start 0.2794 0.1778)
							(mid 0.249642 0.249642)
							(end 0.1778 0.2794)
						)
					)
					(width 0)
					(fill yes)
				)
			)
		)
	)
	(footprint ""
		(layer "B.Cu")
		(at 241.6048 -37.0586 180)
		(property "Reference" "R6"
			(at 0 0 0)
			(layer "B.SilkS")
			(hide yes)
			(effects
				(font
					(size 1.27 1.27)
				)
				(justify mirror)
			)
		)
		(property "Value" "33R1J-GP"
			(at 3.3274 -1.3335 180)
			(unlocked yes)
			(layer "B.Fab")
			(hide yes)
			(effects
				(font
					(size 1.016 1.016)
					(thickness 0.1524)
				)
				(justify mirror)
			)
		)
		(property "Device Type" "R0201H12"
			(at 3.3274 -2.8575 180)
			(unlocked yes)
			(layer "B.Fab")
			(hide yes)
			(effects
				(font
					(size 1.016 1.016)
					(thickness 0.1524)
				)
				(justify mirror)
			)
		)
		(duplicate_pad_numbers_are_jumpers no)
		(fp_rect
			(start 0.2794 0.6477)
			(end -0.2794 -0.6477)
			(stroke
				(width 0)
				(type default)
			)
			(fill no)
			(layer "B.CrtYd")
		)
		(fp_rect
			(start 0.2794 0.6477)
			(end -0.2794 -0.6477)
			(stroke
				(width 0)
				(type default)
			)
			(fill no)
			(layer "B.Fab")
		)
		(pad "1" smd custom
			(at 0 -0.2794)
			(size 0.0762 0.0762)
			(layers "B.Cu" "B.Mask" "B.Paste")
			(net "PCIE_REFCLK_H0_N")
			(options
				(clearance outline)
				(anchor circle)
			)
			(primitives
				(gr_poly
					(pts
						(arc
							(start 0.1524 0.127)
							(mid 0.137521 0.162921)
							(end 0.1016 0.1778)
						)
						(arc
							(start -0.1016 0.1778)
							(mid -0.137521 0.162921)
							(end -0.1524 0.127)
						)
						(arc
							(start -0.1524 -0.127)
							(mid -0.137521 -0.162921)
							(end -0.1016 -0.1778)
						)
						(arc
							(start 0.1016 -0.1778)
							(mid 0.137521 -0.162921)
							(end 0.1524 -0.127)
						)
					)
					(width 0)
					(fill yes)
				)
			)
		)
		(pad "2" smd custom
			(at 0 0.2794)
			(size 0.0762 0.0762)
			(layers "B.Cu" "B.Mask" "B.Paste")
			(net "PCIE_REFCLK_H0_P")
			(options
				(clearance outline)
				(anchor circle)
			)
			(primitives
				(gr_poly
					(pts
						(arc
							(start 0.1524 0.127)
							(mid 0.137521 0.162921)
							(end 0.1016 0.1778)
						)
						(arc
							(start -0.1016 0.1778)
							(mid -0.137521 0.162921)
							(end -0.1524 0.127)
						)
						(arc
							(start -0.1524 -0.127)
							(mid -0.137521 -0.162921)
							(end -0.1016 -0.1778)
						)
						(arc
							(start 0.1016 -0.1778)
							(mid 0.137521 -0.162921)
							(end 0.1524 -0.127)
						)
					)
					(width 0)
					(fill yes)
				)
			)
		)
	)
	(footprint ""
		(layer "B.Cu")
		(at 321.673728 -38.896798)
		(property "Reference" "C254"
			(at 0 0 0)
			(layer "B.SilkS")
			(hide yes)
			(effects
				(font
					(size 1.27 1.27)
				)
				(justify mirror)
			)
		)
		(property "Value" "SCD1U10V2KX-5GP"
			(at -1.1811 -2.7051 0)
			(unlocked yes)
			(layer "B.Fab")
			(hide yes)
			(effects
				(font
					(size 1.016 1.016)
					(thickness 0.1524)
				)
				(justify mirror)
			)
		)
		(property "Device Type" "C402H22"
			(at -1.1811 -4.2291 0)
			(unlocked yes)
			(layer "B.Fab")
			(hide yes)
			(effects
				(font
					(size 1.016 1.016)
					(thickness 0.1524)
				)
				(justify mirror)
			)
		)
		(duplicate_pad_numbers_are_jumpers no)
		(fp_rect
			(start 0.4318 0.9525)
			(end -0.4318 -0.9525)
			(stroke
				(width 0)
				(type default)
			)
			(fill no)
			(layer "B.CrtYd")
		)
		(fp_rect
			(start 0.4318 0.9525)
			(end -0.4318 -0.9525)
			(stroke
				(width 0)
				(type default)
			)
			(fill no)
			(layer "B.Fab")
		)
		(pad "1" smd custom
			(at 0 -0.4445 180)
			(size 0.1524 0.1524)
			(layers "B.Cu" "B.Mask" "B.Paste")
			(net "GND")
			(options
				(clearance outline)
				(anchor circle)
			)
			(primitives
				(gr_poly
					(pts
						(arc
							(start 0.3048 0.2032)
							(mid 0.275042 0.275042)
							(end 0.2032 0.3048)
						)
						(arc
							(start -0.2032 0.3048)
							(mid -0.275042 0.275042)
							(end -0.3048 0.2032)
						)
						(arc
							(start -0.3048 -0.2032)
							(mid -0.275042 -0.275042)
							(end -0.2032 -0.3048)
						)
						(arc
							(start 0.2032 -0.3048)
							(mid 0.275042 -0.275042)
							(end 0.3048 -0.2032)
						)
					)
					(width 0)
					(fill yes)
				)
			)
		)
		(pad "2" smd custom
			(at 0 0.4445 180)
			(size 0.1524 0.1524)
			(layers "B.Cu" "B.Mask" "B.Paste")
			(net "P3V3_STBY")
			(options
				(clearance outline)
				(anchor circle)
			)
			(primitives
				(gr_poly
					(pts
						(arc
							(start 0.3048 0.2032)
							(mid 0.275042 0.275042)
							(end 0.2032 0.3048)
						)
						(arc
							(start -0.2032 0.3048)
							(mid -0.275042 0.275042)
							(end -0.3048 0.2032)
						)
						(arc
							(start -0.3048 -0.2032)
							(mid -0.275042 -0.275042)
							(end -0.2032 -0.3048)
						)
						(arc
							(start 0.2032 -0.3048)
							(mid 0.275042 -0.275042)
							(end 0.3048 -0.2032)
						)
					)
					(width 0)
					(fill yes)
				)
			)
		)
	)
	(footprint ""
		(layer "B.Cu")
		(at 223.393 -20.447)
		(property "Reference" "R3708"
			(at 0 0 0)
			(layer "B.SilkS")
			(hide yes)
			(effects
				(font
					(size 1.27 1.27)
				)
				(justify mirror)
			)
		)
		(property "Value" "4K7R2F-GP"
			(at -0.064008 -3.993896 0)
			(unlocked yes)
			(layer "B.Fab")
			(hide yes)
			(effects
				(font
					(size 1.016 1.016)
					(thickness 0.1524)
				)
				(justify mirror)
			)
		)
		(property "Device Type" "R402H16"
			(at -0.064008 -5.517896 0)
			(unlocked yes)
			(layer "B.Fab")
			(hide yes)
			(effects
				(font
					(size 1.016 1.016)
					(thickness 0.1524)
				)
				(justify mirror)
			)
		)
		(duplicate_pad_numbers_are_jumpers no)
		(fp_line
			(start -0.508 -0.9398)
			(end 0.508 -0.9398)
			(stroke
				(width 0.1524)
				(type default)
			)
			(layer "B.SilkS")
		)
		(fp_line
			(start 0.508 -0.9398)
			(end 0.508 0.9398)
			(stroke
				(width 0.1524)
				(type default)
			)
			(layer "B.SilkS")
		)
		(fp_rect
			(start 0.508 0.9398)
			(end -0.508 -0.9398)
			(stroke
				(width 0)
				(type default)
			)
			(fill no)
			(layer "B.CrtYd")
		)
		(fp_rect
			(start 0.508 0.9398)
			(end -0.508 -0.9398)
			(stroke
				(width 0)
				(type default)
			)
			(fill no)
			(layer "B.Fab")
		)
		(pad "1" smd custom
			(at 0 -0.4445 180)
			(size 0.1397 0.1397)
			(layers "B.Cu" "B.Mask" "B.Paste")
			(net "HOST7_RST_N_LS")
			(options
				(clearance outline)
				(anchor circle)
			)
			(primitives
				(gr_poly
					(pts
						(arc
							(start -0.1778 0.2794)
							(mid -0.249642 0.249642)
							(end -0.2794 0.1778)
						)
						(arc
							(start -0.2794 -0.1778)
							(mid -0.249642 -0.249642)
							(end -0.1778 -0.2794)
						)
						(arc
							(start 0.1778 -0.2794)
							(mid 0.249642 -0.249642)
							(end 0.2794 -0.1778)
						)
						(arc
							(start 0.2794 0.1778)
							(mid 0.249642 0.249642)
							(end 0.1778 0.2794)
						)
					)
					(width 0)
					(fill yes)
				)
			)
		)
		(pad "2" smd custom
			(at 0 0.4445 180)
			(size 0.1397 0.1397)
			(layers "B.Cu" "B.Mask" "B.Paste")
			(net "DUT_VDDO")
			(options
				(clearance outline)
				(anchor circle)
			)
			(primitives
				(gr_poly
					(pts
						(arc
							(start -0.1778 0.2794)
							(mid -0.249642 0.249642)
							(end -0.2794 0.1778)
						)
						(arc
							(start -0.2794 -0.1778)
							(mid -0.249642 -0.249642)
							(end -0.1778 -0.2794)
						)
						(arc
							(start 0.1778 -0.2794)
							(mid 0.249642 -0.249642)
							(end 0.2794 -0.1778)
						)
						(arc
							(start 0.2794 0.1778)
							(mid 0.249642 0.249642)
							(end 0.1778 0.2794)
						)
					)
					(width 0)
					(fill yes)
				)
			)
		)
	)
)
